# S9S_MB_2U (Grand Teton) — schematic netlist excerpt (pin names and nets, part order shuffled) for the footprints in the layout excerpt that follows; sources: Cadence DE-HDL packaged netlist, KiCad conversion of 03242023_DA0F0TMBIJ0_F0T_Motherboard_J_brd_V01_OCP.brd

PC434  Q_CAP  100NF 50V 10% X7R  pkg C0402  page 294 : A = PVCCFA_EHV_CPU1 ; B = GND
C754  Q_CAP_DIFFBUS  DIFF BUS_0.22UF 6.3V 20% X6S  pkg C0201  page 176 : \1\ = P5E_CPU1_PE2_TX_C_DN<9> ; \2\ = P5E_CPU1_PE2_TX_DN<9>
C2269  Q_CAP  1000PF 50V 5% EMPTY  pkg 0402  page 146 : A = PRSNT_CABLE_GPU_A2_ISO_N ; B = GND

(kicad_pcb
	(version 20260206)
	(generator "pcbnew")
	(generator_version "10.0")
	(general
		(thickness 1.6)
		(legacy_teardrops no)
	)
	(paper "A4")
	(title_block
		(title "03242023_DA0F0TMBIJ0_F0T_Motherboard_J_brd_V01_OCP.brd")
		(comment 1 "Grand Teton / footprints 2600-2602 of 6105")
	)
	(layers
		(0 "F.Cu" signal "TOP")
		(4 "In1.Cu" signal "GND")
		(6 "In2.Cu" signal "IN1")
		(8 "In3.Cu" signal "GND1")
		(10 "In4.Cu" signal "IN2")
		(12 "In5.Cu" signal "GND2")
		(14 "In6.Cu" signal "IN3")
		(16 "In7.Cu" signal "GND3")
		(18 "In8.Cu" signal "VCC")
		(20 "In9.Cu" signal "VCC1")
		(22 "In10.Cu" signal "GND4")
		(24 "In11.Cu" signal "IN4")
		(26 "In12.Cu" signal "GND5")
		(28 "In13.Cu" signal "IN5")
		(30 "In14.Cu" signal "GND6")
		(32 "In15.Cu" signal "IN6")
		(34 "In16.Cu" signal "GND7")
		(2 "B.Cu" signal "BOTTOM")
		(9 "F.Adhes" user "F.Adhesive")
		(11 "B.Adhes" user "B.Adhesive")
		(13 "F.Paste" user "Package Geometry/Pastemask Top")
		(15 "B.Paste" user "Package Geometry/Pastemask Bottom")
		(5 "F.SilkS" user "Ref Des/Silkscreen Top")
		(7 "B.SilkS" user "Ref Des/Silkscreen Bottom")
		(1 "F.Mask" user "Board Geometry/Soldermask Top")
		(3 "B.Mask" user "Board Geometry/Soldermask Bottom")
		(17 "Dwgs.User" user "User.Drawings")
		(19 "Cmts.User" user "User.Comments")
		(21 "Eco1.User" user "User.Eco1")
		(23 "Eco2.User" user "User.Eco2")
		(25 "Edge.Cuts" user "Board Geometry/Outline")
		(27 "Margin" user)
		(31 "F.CrtYd" user "Package Geometry/Place Bound Top")
		(29 "B.CrtYd" user "Package Geometry/Place Bound Bottom")
		(35 "F.Fab" user "Ref Des/Assembly Top")
		(33 "B.Fab" user "Ref Des/Assembly Bottom")
	)
	(footprint ""
		(layer "F.Cu")
		(at 306.83454 -430.6697 -90)
		(property "Reference" "C2269"
			(at 0 0 270)
			(layer "F.SilkS")
			(hide yes)
			(effects
				(font
					(size 1.27 1.27)
				)
			)
		)
		(property "Value" ""
			(at 0 0 270)
			(layer "F.Fab")
			(effects
				(font
					(size 1.27 1.27)
				)
			)
		)
		(duplicate_pad_numbers_are_jumpers no)
		(fp_line
			(start -0.7874 0.4064)
			(end -0.7874 -0.4064)
			(stroke
				(width 0.1524)
				(type default)
			)
			(layer "F.SilkS")
		)
		(fp_line
			(start 0.7874 0.4064)
			(end -0.7874 0.4064)
			(stroke
				(width 0.1524)
				(type default)
			)
			(layer "F.SilkS")
		)
		(fp_line
			(start -0.7874 -0.4064)
			(end 0.7874 -0.4064)
			(stroke
				(width 0.1524)
				(type default)
			)
			(layer "F.SilkS")
		)
		(fp_line
			(start 0.7874 -0.4064)
			(end 0.7874 0.4064)
			(stroke
				(width 0.1524)
				(type default)
			)
			(layer "F.SilkS")
		)
		(fp_line
			(start -0.67945 0.3048)
			(end -0.67945 -0.305054)
			(stroke
				(width 0.1)
				(type default)
			)
			(layer "F.Fab")
		)
		(fp_line
			(start -0.12065 0.3048)
			(end -0.67945 0.3048)
			(stroke
				(width 0.1)
				(type default)
			)
			(layer "F.Fab")
		)
		(fp_line
			(start 0.120396 0.3048)
			(end 0.120396 0.2794)
			(stroke
				(width 0.1)
				(type default)
			)
			(layer "F.Fab")
		)
		(fp_line
			(start 0.67945 0.3048)
			(end 0.120396 0.3048)
			(stroke
				(width 0.1)
				(type default)
			)
			(layer "F.Fab")
		)
		(fp_line
			(start -0.12065 0.2794)
			(end -0.12065 0.3048)
			(stroke
				(width 0.1)
				(type default)
			)
			(layer "F.Fab")
		)
		(fp_line
			(start 0.120396 0.2794)
			(end -0.12065 0.2794)
			(stroke
				(width 0.1)
				(type default)
			)
			(layer "F.Fab")
		)
		(fp_line
			(start -0.12065 -0.2794)
			(end 0.12065 -0.2794)
			(stroke
				(width 0.1)
				(type default)
			)
			(layer "F.Fab")
		)
		(fp_line
			(start 0.12065 -0.2794)
			(end 0.12065 -0.3048)
			(stroke
				(width 0.1)
				(type default)
			)
			(layer "F.Fab")
		)
		(fp_line
			(start 0.12065 -0.3048)
			(end 0.67945 -0.3048)
			(stroke
				(width 0.1)
				(type default)
			)
			(layer "F.Fab")
		)
		(fp_line
			(start 0.67945 -0.3048)
			(end 0.67945 0.3048)
			(stroke
				(width 0.1)
				(type default)
			)
			(layer "F.Fab")
		)
		(fp_line
			(start -0.67945 -0.305054)
			(end -0.12065 -0.305054)
			(stroke
				(width 0.1)
				(type default)
			)
			(layer "F.Fab")
		)
		(fp_line
			(start -0.12065 -0.305054)
			(end -0.12065 -0.2794)
			(stroke
				(width 0.1)
				(type default)
			)
			(layer "F.Fab")
		)
		(pad "1" smd circle
			(at -0.40005 0 270)
			(size 0 0)
			(layers "F.Cu" "F.Mask" "F.Paste")
			(net "PRSNT_CABLE_GPU_A2_ISO_N")
		)
		(pad "2" smd circle
			(at 0.40005 0 270)
			(size 0 0)
			(layers "F.Cu" "F.Mask" "F.Paste")
			(net "GND")
		)
	)
	(footprint ""
		(layer "F.Cu")
		(at 139.423394 -402.371052 -90)
		(property "Reference" "C754"
			(at 0 0 270)
			(layer "F.SilkS")
			(hide yes)
			(effects
				(font
					(size 1.27 1.27)
				)
			)
		)
		(property "Value" ""
			(at 0 0 270)
			(layer "F.Fab")
			(effects
				(font
					(size 1.27 1.27)
				)
			)
		)
		(duplicate_pad_numbers_are_jumpers no)
		(fp_line
			(start -0.299974 0.150114)
			(end -0.299974 -0.150114)
			(stroke
				(width 0.1)
				(type default)
			)
			(layer "F.Fab")
		)
		(fp_line
			(start 0.299974 0.150114)
			(end -0.299974 0.150114)
			(stroke
				(width 0.1)
				(type default)
			)
			(layer "F.Fab")
		)
		(fp_line
			(start -0.299974 -0.150114)
			(end 0.299974 -0.150114)
			(stroke
				(width 0.1)
				(type default)
			)
			(layer "F.Fab")
		)
		(fp_line
			(start 0.299974 -0.150114)
			(end 0.299974 0.150114)
			(stroke
				(width 0.1)
				(type default)
			)
			(layer "F.Fab")
		)
		(pad "1" smd rect
			(at -0.2667 0 270)
			(size 0.3048 0.381)
			(layers "F.Cu" "F.Mask" "F.Paste")
			(net "P5E_CPU1_PE2_TX_C_DN<9>")
		)
		(pad "2" smd rect
			(at 0.2667 0 270)
			(size 0.3048 0.381)
			(layers "F.Cu" "F.Mask" "F.Paste")
			(net "P5E_CPU1_PE2_TX_DN<9>")
		)
	)
	(footprint ""
		(layer "F.Cu")
		(at 61.980572 -178.662838 180)
		(property "Reference" "PC434"
			(at 0 0 180)
			(layer "F.SilkS")
			(hide yes)
			(effects
				(font
					(size 1.27 1.27)
				)
			)
		)
		(property "Value" ""
			(at 0 0 180)
			(layer "F.Fab")
			(effects
				(font
					(size 1.27 1.27)
				)
			)
		)
		(duplicate_pad_numbers_are_jumpers no)
		(fp_line
			(start 0.7874 0.4064)
			(end -0.7874 0.4064)
			(stroke
				(width 0.1524)
				(type default)
			)
			(layer "F.SilkS")
		)
		(fp_line
			(start 0.7874 -0.4064)
			(end 0.7874 0.4064)
			(stroke
				(width 0.1524)
				(type default)
			)
			(layer "F.SilkS")
		)
		(fp_line
			(start -0.7874 0.4064)
			(end -0.7874 -0.4064)
			(stroke
				(width 0.1524)
				(type default)
			)
			(layer "F.SilkS")
		)
		(fp_line
			(start -0.7874 -0.4064)
			(end 0.7874 -0.4064)
			(stroke
				(width 0.1524)
				(type default)
			)
			(layer "F.SilkS")
		)
		(fp_line
			(start 0.67945 0.3048)
			(end 0.120396 0.3048)
			(stroke
				(width 0.1)
				(type default)
			)
			(layer "F.Fab")
		)
		(fp_line
			(start 0.67945 -0.3048)
			(end 0.67945 0.3048)
			(stroke
				(width 0.1)
				(type default)
			)
			(layer "F.Fab")
		)
		(fp_line
			(start 0.12065 -0.2794)
			(end 0.12065 -0.3048)
			(stroke
				(width 0.1)
				(type default)
			)
			(layer "F.Fab")
		)
		(fp_line
			(start 0.12065 -0.3048)
			(end 0.67945 -0.3048)
			(stroke
				(width 0.1)
				(type default)
			)
			(layer "F.Fab")
		)
		(fp_line
			(start 0.120396 0.3048)
			(end 0.120396 0.2794)
			(stroke
				(width 0.1)
				(type default)
			)
			(layer "F.Fab")
		)
		(fp_line
			(start 0.120396 0.2794)
			(end -0.12065 0.2794)
			(stroke
				(width 0.1)
				(type default)
			)
			(layer "F.Fab")
		)
		(fp_line
			(start -0.12065 0.3048)
			(end -0.67945 0.3048)
			(stroke
				(width 0.1)
				(type default)
			)
			(layer "F.Fab")
		)
		(fp_line
			(start -0.12065 0.2794)
			(end -0.12065 0.3048)
			(stroke
				(width 0.1)
				(type default)
			)
			(layer "F.Fab")
		)
		(fp_line
			(start -0.12065 -0.2794)
			(end 0.12065 -0.2794)
			(stroke
				(width 0.1)
				(type default)
			)
			(layer "F.Fab")
		)
		(fp_line
			(start -0.12065 -0.305054)
			(end -0.12065 -0.2794)
			(stroke
				(width 0.1)
				(type default)
			)
			(layer "F.Fab")
		)
		(fp_line
			(start -0.67945 0.3048)
			(end -0.67945 -0.305054)
			(stroke
				(width 0.1)
				(type default)
			)
			(layer "F.Fab")
		)
		(fp_line
			(start -0.67945 -0.305054)
			(end -0.12065 -0.305054)
			(stroke
				(width 0.1)
				(type default)
			)
			(layer "F.Fab")
		)
		(pad "1" smd circle
			(at -0.40005 0 180)
			(size 0 0)
			(layers "F.Cu" "F.Mask" "F.Paste")
			(net "PVCCFA_EHV_CPU1")
		)
		(pad "2" smd circle
			(at 0.40005 0 180)
			(size 0 0)
			(layers "F.Cu" "F.Mask" "F.Paste")
			(net "GND")
		)
	)
)
